# BASEBOARD_FAB2 (Tioga Pass) — schematic netlist excerpt (pin names and nets, part order shuffled) for the footprints in the layout excerpt that follows; sources: Cadence DE-HDL packaged netlist, KiCad conversion of Wiwynn_Tioga_Pass_MB.brd

UN8F2  W25Q256  IC  pkg XSOI  page 246
  HOLD_N_IO(3)  = PU_TPM_SPI_BMC_HOLD_N
  VCC  = P3V3_STBY
  RESET_N  = PU_TPM_SPI_FLASH_RESET_2_N
  NC(6)  = TP_TPM_SPI_6
  NC(5)  = TP_TPM_SPI_5
  NC(4)  = TP_TPM_SPI_4
  CS_N  = SPI_BMC_BT_CS0_N
  DO_IO(1)  = SPI_TPM_BMC_DI_R
  WP_N_IO(2)  = TPM_SPI_BMC_WP_N
  GND  = GND
  NC(3)  = TP_TPM_SPI_3
  NC(2)  = TP_TPM_SPI_2
  NC(1)  = TP_TPM_SPI_1
  NC(0)  = TP_TPM_SPI_0
  DI_IO(0)  = SPI_BMC_BT_DO
  CLK  = SPI_BMC_BT_CLK

(kicad_pcb
	(version 20260206)
	(generator "pcbnew")
	(generator_version "10.0")
	(general
		(thickness 1.6)
		(legacy_teardrops no)
	)
	(paper "A4")
	(title_block
		(title "Wiwynn_Tioga_Pass_MB.brd")
		(comment 1 "Tioga Pass / footprints 2260-2260 of 4770")
	)
	(layers
		(0 "F.Cu" signal "TOP")
		(4 "In1.Cu" signal "L2GND")
		(6 "In2.Cu" signal "L3")
		(8 "In3.Cu" signal "L4GND")
		(10 "In4.Cu" signal "L5")
		(12 "In5.Cu" signal "L6GND")
		(14 "In6.Cu" signal "L7VCC")
		(16 "In7.Cu" signal "L8VCC")
		(18 "In8.Cu" signal "L9GND")
		(20 "In9.Cu" signal "L10")
		(22 "In10.Cu" signal "L11GND")
		(24 "In11.Cu" signal "L12")
		(26 "In12.Cu" signal "L13GND")
		(2 "B.Cu" signal "BOTTOM")
		(9 "F.Adhes" user "F.Adhesive")
		(11 "B.Adhes" user "B.Adhesive")
		(13 "F.Paste" user "Package Geometry/Pastemask Top")
		(15 "B.Paste" user "Package Geometry/Pastemask Bottom")
		(5 "F.SilkS" user "Ref Des/Silkscreen Top")
		(7 "B.SilkS" user "Ref Des/Silkscreen Bottom")
		(1 "F.Mask" user "Board Geometry/Soldermask Top")
		(3 "B.Mask" user "Board Geometry/Soldermask Bottom")
		(17 "Dwgs.User" user "User.Drawings")
		(19 "Cmts.User" user "User.Comments")
		(21 "Eco1.User" user "User.Eco1")
		(23 "Eco2.User" user "User.Eco2")
		(25 "Edge.Cuts" user "Board Geometry/Outline")
		(27 "Margin" user)
		(31 "F.CrtYd" user "Package Geometry/Place Bound Top")
		(29 "B.CrtYd" user "Package Geometry/Place Bound Bottom")
		(35 "F.Fab" user "Ref Des/Assembly Top")
		(33 "B.Fab" user "Ref Des/Assembly Bottom")
	)
	(footprint ""
		(layer "F.Cu")
		(at 376.879866 -17.869662 180)
		(property "Reference" "UN8F2"
			(at 3.446272 -4.713986 180)
			(unlocked yes)
			(layer "F.SilkS")
			(effects
				(font
					(size 1.27 0.964946)
					(thickness 0.000001)
				)
				(justify left)
			)
		)
		(property "Value" ""
			(at 0 0 180)
			(layer "F.Fab")
			(effects
				(font
					(size 1.27 1.27)
				)
			)
		)
		(duplicate_pad_numbers_are_jumpers no)
		(fp_line
			(start 11.645392 10.819892)
			(end -2.094738 10.819892)
			(stroke
				(width 0.1524)
				(type default)
			)
			(layer "F.SilkS")
		)
		(fp_line
			(start 11.645392 -1.929892)
			(end 11.645392 10.819892)
			(stroke
				(width 0.1524)
				(type default)
			)
			(layer "F.SilkS")
		)
		(fp_line
			(start -2.094738 10.819892)
			(end -2.094738 -1.929892)
			(stroke
				(width 0.1524)
				(type default)
			)
			(layer "F.SilkS")
		)
		(fp_line
			(start -2.094738 -1.929892)
			(end 11.645392 -1.929892)
			(stroke
				(width 0.1524)
				(type default)
			)
			(layer "F.SilkS")
		)
		(fp_circle
			(center -2.69621 -0.952754)
			(end -2.82321 -0.952754)
			(stroke
				(width 0.762)
				(type default)
			)
			(fill no)
			(layer "F.SilkS")
		)
		(fp_rect
			(start 15.404846 -3.284474)
			(end 11.645392 12.260326)
			(stroke
				(width 0)
				(type default)
			)
			(fill no)
			(layer "F.CrtYd")
		)
		(fp_rect
			(start 11.645392 -1.929892)
			(end -2.094738 10.819892)
			(stroke
				(width 0)
				(type default)
			)
			(fill no)
			(layer "F.CrtYd")
		)
		(fp_rect
			(start -2.094738 -3.284474)
			(end -5.600954 12.260326)
			(stroke
				(width 0)
				(type default)
			)
			(fill no)
			(layer "F.CrtYd")
		)
		(fp_poly
			(pts
				(xy 7.569962 10.819892) (xy 6.970014 12.21994) (xy 2.629916 12.21994) (xy 2.029968 10.819892)
			)
			(stroke
				(width 0)
				(type default)
			)
			(fill no)
			(layer "F.CrtYd")
		)
		(fp_poly
			(pts
				(xy 2.029968 -1.929892) (xy 2.629916 -3.32994) (xy 6.970014 -3.32994) (xy 7.569962 -1.929892)
			)
			(stroke
				(width 0)
				(type default)
			)
			(fill no)
			(layer "F.CrtYd")
		)
		(fp_line
			(start 11.645392 10.819892)
			(end -2.094738 10.819892)
			(stroke
				(width 0.1)
				(type default)
			)
			(layer "F.Fab")
		)
		(fp_line
			(start 11.645392 -1.929892)
			(end 11.645392 10.819892)
			(stroke
				(width 0.1)
				(type default)
			)
			(layer "F.Fab")
		)
		(fp_line
			(start 7.569962 10.819892)
			(end 6.970014 12.21994)
			(stroke
				(width 0.1)
				(type default)
			)
			(layer "F.Fab")
		)
		(fp_line
			(start 6.970014 12.21994)
			(end 2.629916 12.21994)
			(stroke
				(width 0.1)
				(type default)
			)
			(layer "F.Fab")
		)
		(fp_line
			(start 6.970014 -3.32994)
			(end 7.569962 -1.929892)
			(stroke
				(width 0.1)
				(type default)
			)
			(layer "F.Fab")
		)
		(fp_line
			(start 2.629916 12.21994)
			(end 2.029968 10.819892)
			(stroke
				(width 0.1)
				(type default)
			)
			(layer "F.Fab")
		)
		(fp_line
			(start 2.629916 -3.32994)
			(end 6.970014 -3.32994)
			(stroke
				(width 0.1)
				(type default)
			)
			(layer "F.Fab")
		)
		(fp_line
			(start 2.029968 -1.929892)
			(end 2.629916 -3.32994)
			(stroke
				(width 0.1)
				(type default)
			)
			(layer "F.Fab")
		)
		(fp_line
			(start -2.094738 10.819892)
			(end -2.094738 -1.929892)
			(stroke
				(width 0.1)
				(type default)
			)
			(layer "F.Fab")
		)
		(fp_line
			(start -2.094738 -1.929892)
			(end 11.645392 -1.929892)
			(stroke
				(width 0.1)
				(type default)
			)
			(layer "F.Fab")
		)
		(pad "1" smd rect
			(at 0 0 180)
			(size 1.9304 0.635)
			(layers "F.Cu" "F.Mask" "F.Paste")
			(net "PU_TPM_SPI_BMC_HOLD_N")
		)
		(pad "2" smd rect
			(at 0 1.27 180)
			(size 1.9304 0.635)
			(layers "F.Cu" "F.Mask" "F.Paste")
			(net "P3V3_STBY")
		)
		(pad "3" smd rect
			(at 0 2.54 180)
			(size 1.9304 0.635)
			(layers "F.Cu" "F.Mask" "F.Paste")
			(net "PU_TPM_SPI_FLASH_RESET_2_N")
		)
		(pad "4" smd rect
			(at 0 3.81 180)
			(size 1.9304 0.635)
			(layers "F.Cu" "F.Mask" "F.Paste")
			(net "TP_TPM_SPI_6")
		)
		(pad "5" smd rect
			(at 0 5.08 180)
			(size 1.9304 0.635)
			(layers "F.Cu" "F.Mask" "F.Paste")
			(net "TP_TPM_SPI_5")
		)
		(pad "6" smd rect
			(at 0 6.35 180)
			(size 1.9304 0.635)
			(layers "F.Cu" "F.Mask" "F.Paste")
			(net "TP_TPM_SPI_4")
		)
		(pad "7" smd rect
			(at 0 7.62 180)
			(size 1.9304 0.635)
			(layers "F.Cu" "F.Mask" "F.Paste")
			(net "SPI_BMC_BT_CS0_N")
		)
		(pad "8" smd rect
			(at 0 8.89 180)
			(size 1.9304 0.635)
			(layers "F.Cu" "F.Mask" "F.Paste")
			(net "SPI_TPM_BMC_DI_R")
		)
		(pad "9" smd rect
			(at 9.5504 8.89 180)
			(size 1.9304 0.635)
			(layers "F.Cu" "F.Mask" "F.Paste")
			(net "TPM_SPI_BMC_WP_N")
		)
		(pad "10" smd rect
			(at 9.5504 7.62 180)
			(size 1.9304 0.635)
			(layers "F.Cu" "F.Mask" "F.Paste")
			(net "GND")
		)
		(pad "11" smd rect
			(at 9.5504 6.35 180)
			(size 1.9304 0.635)
			(layers "F.Cu" "F.Mask" "F.Paste")
			(net "TP_TPM_SPI_3")
		)
		(pad "12" smd rect
			(at 9.5504 5.08 180)
			(size 1.9304 0.635)
			(layers "F.Cu" "F.Mask" "F.Paste")
			(net "TP_TPM_SPI_2")
		)
		(pad "13" smd rect
			(at 9.5504 3.81 180)
			(size 1.9304 0.635)
			(layers "F.Cu" "F.Mask" "F.Paste")
			(net "TP_TPM_SPI_1")
		)
		(pad "14" smd rect
			(at 9.5504 2.54 180)
			(size 1.9304 0.635)
			(layers "F.Cu" "F.Mask" "F.Paste")
			(net "TP_TPM_SPI_0")
		)
		(pad "15" smd rect
			(at 9.5504 1.27 180)
			(size 1.9304 0.635)
			(layers "F.Cu" "F.Mask" "F.Paste")
			(net "SPI_BMC_BT_DO")
		)
		(pad "16" smd rect
			(at 9.5504 0 180)
			(size 1.9304 0.635)
			(layers "F.Cu" "F.Mask" "F.Paste")
			(net "SPI_BMC_BT_CLK")
		)
	)
)
